# S9S_MB_2U (Grand Teton) — schematic netlist excerpt (pin names and nets, part order shuffled) for the footprints in the layout excerpt that follows; sources: Cadence DE-HDL packaged netlist, KiCad conversion of 03242023_DA0F0TMBIJ0_F0T_Motherboard_J_brd_V01_OCP.brd

PR4523  Q_RES  10M 1% CHIP  pkg 0402LF  page 162 : A = P3V3_OCP_V3_2_R ; B = P3V3_OCP_GATE_2

Q107  MOSFET_NCH_DUAL  PJT138K IC  pkg SOT363XD  page 147
  S1  = GND
  G1  = GPU_PRSNT_N
  D2  = GPU_PRSNT_N_ISO
  S2  = GND
  G2  = GPU_PRSNT
  D1  = GPU_PRSNT

C851  Q_CAP_DIFFBUS  DIFF BUS_0.22UF 6.3V 20% X6S  pkg C0201  page 174 : \1\ = P5E_CPU0_PE1_TX_C_DP<9> ; \2\ = P5E_CPU0_PE1_TX_DP<9>

(kicad_pcb
	(version 20260206)
	(generator "pcbnew")
	(generator_version "10.0")
	(general
		(thickness 1.6)
		(legacy_teardrops no)
	)
	(paper "A4")
	(title_block
		(title "03242023_DA0F0TMBIJ0_F0T_Motherboard_J_brd_V01_OCP.brd")
		(comment 1 "Grand Teton / footprints 806-808 of 6105")
	)
	(layers
		(0 "F.Cu" signal "TOP")
		(4 "In1.Cu" signal "GND")
		(6 "In2.Cu" signal "IN1")
		(8 "In3.Cu" signal "GND1")
		(10 "In4.Cu" signal "IN2")
		(12 "In5.Cu" signal "GND2")
		(14 "In6.Cu" signal "IN3")
		(16 "In7.Cu" signal "GND3")
		(18 "In8.Cu" signal "VCC")
		(20 "In9.Cu" signal "VCC1")
		(22 "In10.Cu" signal "GND4")
		(24 "In11.Cu" signal "IN4")
		(26 "In12.Cu" signal "GND5")
		(28 "In13.Cu" signal "IN5")
		(30 "In14.Cu" signal "GND6")
		(32 "In15.Cu" signal "IN6")
		(34 "In16.Cu" signal "GND7")
		(2 "B.Cu" signal "BOTTOM")
		(9 "F.Adhes" user "F.Adhesive")
		(11 "B.Adhes" user "B.Adhesive")
		(13 "F.Paste" user "Package Geometry/Pastemask Top")
		(15 "B.Paste" user "Package Geometry/Pastemask Bottom")
		(5 "F.SilkS" user "Ref Des/Silkscreen Top")
		(7 "B.SilkS" user "Ref Des/Silkscreen Bottom")
		(1 "F.Mask" user "Board Geometry/Soldermask Top")
		(3 "B.Mask" user "Board Geometry/Soldermask Bottom")
		(17 "Dwgs.User" user "User.Drawings")
		(19 "Cmts.User" user "User.Comments")
		(21 "Eco1.User" user "User.Eco1")
		(23 "Eco2.User" user "User.Eco2")
		(25 "Edge.Cuts" user "Board Geometry/Outline")
		(27 "Margin" user)
		(31 "F.CrtYd" user "Package Geometry/Place Bound Top")
		(29 "B.CrtYd" user "Package Geometry/Place Bound Bottom")
		(35 "F.Fab" user "Ref Des/Assembly Top")
		(33 "B.Fab" user "Ref Des/Assembly Bottom")
	)
	(footprint ""
		(layer "F.Cu")
		(at 28.081732 -411.434534)
		(property "Reference" "Q107"
			(at 0.0508 -2.306828 0)
			(unlocked yes)
			(layer "F.SilkS")
			(effects
				(font
					(size 0.7874 0.5842)
					(thickness 0.1524)
				)
				(justify left)
			)
		)
		(property "Value" ""
			(at 0 0 0)
			(layer "F.Fab")
			(effects
				(font
					(size 1.27 1.27)
				)
			)
		)
		(duplicate_pad_numbers_are_jumpers no)
		(fp_line
			(start -1.332738 -1.100074)
			(end -0.4826 -1.100074)
			(stroke
				(width 0.1524)
				(type default)
			)
			(layer "F.SilkS")
		)
		(fp_line
			(start -1.332738 1.100074)
			(end -1.332738 -1.100074)
			(stroke
				(width 0.1524)
				(type default)
			)
			(layer "F.SilkS")
		)
		(fp_line
			(start -0.4826 -1.100074)
			(end 0 -0.541274)
			(stroke
				(width 0.1524)
				(type default)
			)
			(layer "F.SilkS")
		)
		(fp_line
			(start 0 -0.541274)
			(end 0.4826 -1.100074)
			(stroke
				(width 0.1524)
				(type default)
			)
			(layer "F.SilkS")
		)
		(fp_line
			(start 0.4826 -1.100074)
			(end 1.332738 -1.100074)
			(stroke
				(width 0.1524)
				(type default)
			)
			(layer "F.SilkS")
		)
		(fp_line
			(start 1.332738 -1.100074)
			(end 1.332738 1.100074)
			(stroke
				(width 0.1524)
				(type default)
			)
			(layer "F.SilkS")
		)
		(fp_line
			(start 1.332738 1.100074)
			(end -1.332738 1.100074)
			(stroke
				(width 0.1524)
				(type default)
			)
			(layer "F.SilkS")
		)
		(fp_poly
			(pts
				(xy -0.542544 -1.945132) (xy -0.893572 -1.24333) (xy -1.2446 -1.945132)
			)
			(stroke
				(width 0)
				(type default)
			)
			(fill yes)
			(layer "F.SilkS")
		)
		(fp_line
			(start -0.674878 -1.100074)
			(end 0.674878 -1.100074)
			(stroke
				(width 0.1)
				(type default)
			)
			(layer "F.Fab")
		)
		(fp_line
			(start -0.674878 1.100074)
			(end -0.674878 -1.100074)
			(stroke
				(width 0.1)
				(type default)
			)
			(layer "F.Fab")
		)
		(fp_line
			(start 0.674878 -1.100074)
			(end 0.674878 1.100074)
			(stroke
				(width 0.1)
				(type default)
			)
			(layer "F.Fab")
		)
		(fp_line
			(start 0.674878 1.100074)
			(end -0.674878 1.100074)
			(stroke
				(width 0.1)
				(type default)
			)
			(layer "F.Fab")
		)
		(fp_poly
			(pts
				(xy -2.2352 -0.298958) (xy -2.2352 -1.001014) (xy -1.533144 -0.649986)
			)
			(stroke
				(width 0)
				(type default)
			)
			(fill yes)
			(layer "F.Fab")
		)
		(pad "1" smd rect
			(at -0.94996 -0.649986 90)
			(size 0.4318 0.508)
			(layers "F.Cu" "F.Mask" "F.Paste")
			(net "GND")
		)
		(pad "2" smd rect
			(at -0.94996 0 90)
			(size 0.4318 0.508)
			(layers "F.Cu" "F.Mask" "F.Paste")
			(net "GPU_PRSNT_N")
		)
		(pad "3" smd rect
			(at -0.94996 0.649986 90)
			(size 0.4318 0.508)
			(layers "F.Cu" "F.Mask" "F.Paste")
			(net "GPU_PRSNT_N_ISO")
		)
		(pad "4" smd rect
			(at 0.94996 0.649986 90)
			(size 0.4318 0.508)
			(layers "F.Cu" "F.Mask" "F.Paste")
			(net "GND")
		)
		(pad "5" smd rect
			(at 0.94996 0 90)
			(size 0.4318 0.508)
			(layers "F.Cu" "F.Mask" "F.Paste")
			(net "GPU_PRSNT")
		)
		(pad "6" smd rect
			(at 0.94996 -0.649986 90)
			(size 0.4318 0.508)
			(layers "F.Cu" "F.Mask" "F.Paste")
			(net "GPU_PRSNT")
		)
	)
	(footprint ""
		(layer "F.Cu")
		(at 87.935562 -53.880258 90)
		(property "Reference" "PR4523"
			(at 0 0 90)
			(layer "F.SilkS")
			(hide yes)
			(effects
				(font
					(size 1.27 1.27)
				)
			)
		)
		(property "Value" ""
			(at 0 0 90)
			(layer "F.Fab")
			(effects
				(font
					(size 1.27 1.27)
				)
			)
		)
		(duplicate_pad_numbers_are_jumpers no)
		(fp_line
			(start 0.7874 -0.4064)
			(end 0.7874 0.4064)
			(stroke
				(width 0.1524)
				(type default)
			)
			(layer "F.SilkS")
		)
		(fp_line
			(start -0.7874 -0.4064)
			(end 0.7874 -0.4064)
			(stroke
				(width 0.1524)
				(type default)
			)
			(layer "F.SilkS")
		)
		(fp_line
			(start 0.7874 0.4064)
			(end -0.7874 0.4064)
			(stroke
				(width 0.1524)
				(type default)
			)
			(layer "F.SilkS")
		)
		(fp_line
			(start -0.7874 0.4064)
			(end -0.7874 -0.4064)
			(stroke
				(width 0.1524)
				(type default)
			)
			(layer "F.SilkS")
		)
		(fp_line
			(start -0.12065 -0.305054)
			(end -0.12065 -0.2794)
			(stroke
				(width 0.1)
				(type default)
			)
			(layer "F.Fab")
		)
		(fp_line
			(start -0.67945 -0.305054)
			(end -0.12065 -0.305054)
			(stroke
				(width 0.1)
				(type default)
			)
			(layer "F.Fab")
		)
		(fp_line
			(start 0.67945 -0.3048)
			(end 0.67945 0.3048)
			(stroke
				(width 0.1)
				(type default)
			)
			(layer "F.Fab")
		)
		(fp_line
			(start 0.12065 -0.3048)
			(end 0.67945 -0.3048)
			(stroke
				(width 0.1)
				(type default)
			)
			(layer "F.Fab")
		)
		(fp_line
			(start 0.12065 -0.2794)
			(end 0.12065 -0.3048)
			(stroke
				(width 0.1)
				(type default)
			)
			(layer "F.Fab")
		)
		(fp_line
			(start -0.12065 -0.2794)
			(end 0.12065 -0.2794)
			(stroke
				(width 0.1)
				(type default)
			)
			(layer "F.Fab")
		)
		(fp_line
			(start 0.120396 0.2794)
			(end -0.12065 0.2794)
			(stroke
				(width 0.1)
				(type default)
			)
			(layer "F.Fab")
		)
		(fp_line
			(start -0.12065 0.2794)
			(end -0.12065 0.3048)
			(stroke
				(width 0.1)
				(type default)
			)
			(layer "F.Fab")
		)
		(fp_line
			(start 0.67945 0.3048)
			(end 0.120396 0.3048)
			(stroke
				(width 0.1)
				(type default)
			)
			(layer "F.Fab")
		)
		(fp_line
			(start 0.120396 0.3048)
			(end 0.120396 0.2794)
			(stroke
				(width 0.1)
				(type default)
			)
			(layer "F.Fab")
		)
		(fp_line
			(start -0.12065 0.3048)
			(end -0.67945 0.3048)
			(stroke
				(width 0.1)
				(type default)
			)
			(layer "F.Fab")
		)
		(fp_line
			(start -0.67945 0.3048)
			(end -0.67945 -0.305054)
			(stroke
				(width 0.1)
				(type default)
			)
			(layer "F.Fab")
		)
		(pad "1" smd circle
			(at -0.40005 0 90)
			(size 0 0)
			(layers "F.Cu" "F.Mask" "F.Paste")
			(net "P3V3_OCP_V3_2_R")
		)
		(pad "2" smd circle
			(at 0.40005 0 90)
			(size 0 0)
			(layers "F.Cu" "F.Mask" "F.Paste")
			(net "P3V3_OCP_GATE_2")
		)
	)
	(footprint ""
		(layer "F.Cu")
		(at 406.779984 -16.088614 90)
		(property "Reference" "C851"
			(at 0 0 90)
			(layer "F.SilkS")
			(hide yes)
			(effects
				(font
					(size 1.27 1.27)
				)
			)
		)
		(property "Value" ""
			(at 0 0 90)
			(layer "F.Fab")
			(effects
				(font
					(size 1.27 1.27)
				)
			)
		)
		(duplicate_pad_numbers_are_jumpers no)
		(fp_line
			(start 0.299974 -0.150114)
			(end 0.299974 0.150114)
			(stroke
				(width 0.1)
				(type default)
			)
			(layer "F.Fab")
		)
		(fp_line
			(start -0.299974 -0.150114)
			(end 0.299974 -0.150114)
			(stroke
				(width 0.1)
				(type default)
			)
			(layer "F.Fab")
		)
		(fp_line
			(start 0.299974 0.150114)
			(end -0.299974 0.150114)
			(stroke
				(width 0.1)
				(type default)
			)
			(layer "F.Fab")
		)
		(fp_line
			(start -0.299974 0.150114)
			(end -0.299974 -0.150114)
			(stroke
				(width 0.1)
				(type default)
			)
			(layer "F.Fab")
		)
		(pad "1" smd rect
			(at -0.2667 0 90)
			(size 0.3048 0.381)
			(layers "F.Cu" "F.Mask" "F.Paste")
			(net "P5E_CPU0_PE1_TX_C_DP<9>")
		)
		(pad "2" smd rect
			(at 0.2667 0 90)
			(size 0.3048 0.381)
			(layers "F.Cu" "F.Mask" "F.Paste")
			(net "P5E_CPU0_PE1_TX_DP<9>")
		)
	)
)
